FILE_TYPE = CONNECTIVITY;
{Allegro Design Entry HDL 16.6-p007 (v16-6-112F) 10/10/2012}
"PAGE_NUMBER" = 112;
0"NC";
1"PVCCIO_CPU0\g";
2"PVCCIO_CPU0\g";
3"P1V05_PCH_STBY\g";
4"GND\g";
5"PVCCIO_CPU0\g";
6"PVCCIO_CPU1\g";
7"GND\g";
8"GND\g";
9"P3V3_STBY\g";
10"P3V3_STBY\g";
11"PVCCIO_CPU0\g";
12"P3V3_STBY\g";
13"P3V3_STBY\g";
14"GND\g";
15"GND\g";
16"PVCCIO_CPU0\g";
17"GND\g";
18"GND\g";
19"XDP_CPU_OBSFN_B1_MBP7_N";
20"XDP_PCH_CPU_TCK0";
21"XDP_CPU_TRST_N";
22"XDP_PREQ_N";
23"XDP_PRDY_N";
24"XDP_OBSFN_B0_MBP6_N";
25"XDP_OBSFN_B1_MBP7_N";
26"PWRGD_PVCCIN_CPU0";
27"XDP_TDI";
28"XDP_TDO";
29"XDP_TMS";
30"XDP_TRST_N";
31"XDP_PCH_TCK1";
32"XDP_TRST_N";
33"XDP_CPU_OBSFN_B1_MBP7_N";
34"XDP_CPU_PREQ_N";
35"XDP_CPU_PRDY_N";
36"XDP_CPU_OBSFN_B0_MBP6_N";
37"XDP_CPU_TDI";
38"XDP_CPU_TDO";
39"XDP_CPU_TMS";
40"XDP_CPU_TRST_N";
41"XDP_PRDY_N";
42"XDP_PREQ_N";
43"XDP_TMS";
44"XDP_TDI";
45"XDP_TDO";
46"XDP_CPU_TCK0";
47"XDP_CPU_PRDY_N";
48"XDP_CPU_PREQ_N";
49"XDP_CPU_TMS";
50"XDP_CPU1_TDI";
51"XDP_CPU_TDI";
52"XDP_CPU0_TDO";
53"XDP_CPU_MBP0_N";
54"XDP_CPU1_TDO";
55"XDP_CPU_MBP1_N";
56"XDP_CPU_MBP0_N";
57"XDP_CPU_MBP1_N";
58"XDP_CPU_OBSFN_B0_MBP6_N";
59"XDP_CPU0_TDO";
60"FM_CPU1_SKTOCC_LVT3_N";
61"XDP_CPU1_TDI";
62"XDP_CPU_TDO";
63"XDP_CPU1_TDO";
64"XDP_CPU0_TDO";
65"FM_CPU1_SKTOCC_LVT3_N";
%"TTL3126"
"3","(-2200,2425)","0","mstr_ttl","I108";
;
POWER_GROUP"VCC=P3V3_STBY;GND=GND"
LOCATION"U1L1"
PART_NUMBER"D18317-001"
VALUE"74CBTLV3126"
MATERIAL"IC"
PACK_TYPE"QFNLF"
HAS_FIXED_SIZE"4B"
CDS_LIB"mstr_ttl"
CDS_LOCATION"U1L1"
ROOM"DEBUG";
"OE <3>"
$SEC"1"
CDS_SEC"1"
$PN"1"26;
"OE <2>"
$SEC"2"
CDS_SEC"2"
$PN"4"26;
"OE <1>"
$SEC"3"
CDS_SEC"3"
$PN"10"26;
"OE <0>"
$SEC"4"
CDS_SEC"4"
$PN"13"26;
"A <3>"
$SEC"1"
CDS_SEC"1"
$PN"2"30;
"A <2>"
$SEC"2"
CDS_SEC"2"
$PN"5"29;
"A <0>"
$SEC"4"
CDS_SEC"4"
$PN"12"27;
"A <1>"
$SEC"3"
CDS_SEC"3"
$PN"9"28;
"B <3>"
$SEC"1"
CDS_SEC"1"
$PN"3"40;
"B <2>"
$SEC"2"
CDS_SEC"2"
$PN"6"39;
"B <1>"
$SEC"3"
CDS_SEC"3"
$PN"8"38;
"B <0>"
$SEC"4"
CDS_SEC"4"
$PN"11"37;
%"TTL3126"
"3","(-2200,1200)","0","mstr_ttl","I109";
;
POWER_GROUP"VCC=P3V3_STBY;GND=GND"
LOCATION"U1L5"
PART_NUMBER"D18317-001"
VALUE"74CBTLV3126"
MATERIAL"IC"
PACK_TYPE"QFNLF"
CDS_LIB"mstr_ttl"
HAS_FIXED_SIZE"4B"
CDS_LOCATION"U1L5"
ROOM"DEBUG";
"OE <3>"
$SEC"1"
CDS_SEC"1"
$PN"1"26;
"OE <2>"
$SEC"2"
CDS_SEC"2"
$PN"4"26;
"OE <1>"
$SEC"3"
CDS_SEC"3"
$PN"10"26;
"OE <0>"
$SEC"4"
CDS_SEC"4"
$PN"13"26;
"A <3>"
$SEC"1"
CDS_SEC"1"
$PN"2"25;
"A <2>"
$SEC"2"
CDS_SEC"2"
$PN"5"24;
"A <0>"
$SEC"4"
CDS_SEC"4"
$PN"12"22;
"A <1>"
$SEC"3"
CDS_SEC"3"
$PN"9"23;
"B <3>"
$SEC"1"
CDS_SEC"1"
$PN"3"33;
"B <2>"
$SEC"2"
CDS_SEC"2"
$PN"6"36;
"B <1>"
$SEC"3"
CDS_SEC"3"
$PN"8"35;
"B <0>"
$SEC"4"
CDS_SEC"4"
$PN"11"34;
%"RES"
"2","(3500,2400)","0","mstr_discrete","I120";
;
CDS_SEC"1"
LOCATION"R6T9"
PART_NUMBER"G21796-017"
VALUE"100.0"
TOLERANCE"1%"
PACK_TYPE"0402"
MATERIAL"CHIP"
WATTAGE"1/16W"
SEC_TYPE"0402"
CDS_LIB"mstr_discrete"
SEC"1"
CDS_LOCATION"R6T9"
ROOM"DEBUG";
"A"
$PN"1"1;
"B"
$PN"2"19;
%"RES"
"2","(3175,2400)","0","mstr_discrete","I121";
;
CDS_SEC"1"
LOCATION"R6T8"
PART_NUMBER"G21796-017"
VALUE"100.0"
TOLERANCE"1%"
PACK_TYPE"0402"
MATERIAL"CHIP"
WATTAGE"1/16W"
SEC_TYPE"0402"
CDS_LIB"mstr_discrete"
SEC"1"
CDS_LOCATION"R6T8"
ROOM"DEBUG";
"A"
$PN"1"1;
"B"
$PN"2"58;
%"PVCCIO_CPU0"
"1","(3500,2700)","0","mstr_symbols","I122";
;
VOLTAGE"1.1V"
CDS_LIB"mstr_symbols"
BODY_TYPE"PLUMBING"
HDL_POWER"PVCCIO_CPU0";
"G\NAC"1;
%"PVCCIO_CPU0"
"1","(1950,2725)","0","mstr_symbols","I123";
;
VOLTAGE"1.1V"
CDS_LIB"mstr_symbols"
BODY_TYPE"PLUMBING"
HDL_POWER"PVCCIO_CPU0";
"G\NAC"2;
%"P1V05_PCH_STBY"
"1","(-1200,4750)","0","mstr_symbols","I126";
;
VOLTAGE"1.05V"
CDS_LIB"mstr_symbols"
BODY_TYPE"PLUMBING"
HDL_POWER"P1V05_PCH_STBY";
"G\NAC"3;
%"74CBTLV1G125"
"1","(3075,3425)","0","mstr_ttl","I127";
;
CDS_SEC"1"
CDS_LOCATION"U1M4"
PACK_TYPE"SMLF"
MATERIAL"IC"
POWER_GROUP"VCC=P3V3_STBY;GND=GND;"
PART_NUMBER"C88177-001"
LOCATION"U1M4"
SEC_TYPE"SMLF"
CDS_LIB"mstr_ttl"
BOM_COST"DEBUG"
SEC"1"
ROOM"DEBUG";
"OE_N \B"
$PN"1"60;
"B"
$PN"4"61;
"A"
$PN"2"59;
%"CAP_A"
"1","(3550,3725)","2","dev_discrete","I131";
;
CDS_LOCATION"C1M30"
LOCATION"C1M30"
PART_NUMBER"A36096-045"
VALUE"0.01UF"
TOLERANCE"10%"
PACK_TYPE"0402V"
VOLTAGE"25V"
MATERIAL"X7R"
BOM_COST"DEBUG"
CDS_LIB"dev_discrete"
CDS_SEC"1"
SEC_TYPE"0402V"
SEC"1"
ROOM"DEBUG";
"B"
$PN"2"4;
"A"
$PN"1"9;
%"GND"
"1","(3550,3525)","0","mstr_symbols","I133";
;
VOLTAGE"0.0V"
SIZE"1B"
BOM_COST"DEBUG"
CDS_LIB"mstr_symbols"
ROOM"CPU_JTAG_DEBUG"
BODY_TYPE"PLUMBING"
HDL_POWER"GND";
"A\NAC"4;
%"PVCCIO_CPU0"
"1","(500,2675)","0","mstr_symbols","I134";
;
VOLTAGE"1.1V"
CDS_LIB"mstr_symbols"
BODY_TYPE"PLUMBING"
HDL_POWER"PVCCIO_CPU0";
"G\NAC"5;
%"PVCCIO_CPU1"
"1","(1225,2675)","0","mstr_symbols","I135";
;
VOLTAGE"1.1V"
CDS_LIB"mstr_symbols"
BODY_TYPE"PLUMBING"
HDL_POWER"PVCCIO_CPU1";
"G\NAC"6;
%"CAP"
"1","(-1125,1850)","0","mstr_discrete","I136";
;
CDS_SEC"1"
LOCATION"C1L1"
PART_NUMBER"D97712-011"
VALUE"1.0UF"
TOLERANCE"10%"
PACK_TYPE"0402"
VOLTAGE"16V"
MATERIAL"X6S"
CDS_LIB"mstr_discrete"
SEC_TYPE"0402"
SEC"1"
CDS_LOCATION"C1L1"
ROOM"DEBUG";
"A"
$PN"1"12;
"B"
$PN"2"7;
%"GND"
"1","(-1125,1675)","0","mstr_symbols","I138";
;
VOLTAGE"0.0V"
CDS_LIB"mstr_symbols"
SIZE"1B"
BODY_TYPE"PLUMBING"
HDL_POWER"GND";
"A\NAC"7;
%"CAP"
"1","(-1350,625)","0","mstr_discrete","I140";
;
CDS_SEC"1"
LOCATION"C1L19"
PART_NUMBER"D97712-011"
VALUE"1.0UF"
TOLERANCE"10%"
PACK_TYPE"0402"
VOLTAGE"16V"
MATERIAL"X6S"
CDS_LIB"mstr_discrete"
SEC_TYPE"0402"
SEC"1"
CDS_LOCATION"C1L19"
ROOM"DEBUG";
"A"
$PN"1"13;
"B"
$PN"2"8;
%"GND"
"1","(-1350,450)","0","mstr_symbols","I141";
;
VOLTAGE"0.0V"
SIZE"1B"
CDS_LIB"mstr_symbols"
BODY_TYPE"PLUMBING"
HDL_POWER"GND";
"A\NAC"8;
%"P3V3_STBY"
"1","(3550,3925)","0","mstr_symbols","I143";
;
VOLTAGE"+3.3V"
CDS_LIB"mstr_symbols"
SIZE"1B"
BODY_TYPE"PLUMBING"
HDL_POWER"P3V3_STBY";
"G\NAC"9;
%"P3V3_STBY"
"1","(2700,4300)","0","mstr_symbols","I144";
;
VOLTAGE"+3.3V"
SIZE"1B"
CDS_LIB"mstr_symbols"
BODY_TYPE"PLUMBING"
HDL_POWER"P3V3_STBY";
"G\NAC"10;
%"PVCCIO_CPU0"
"1","(2675,2700)","0","mstr_symbols","I147";
;
VOLTAGE"1.1V"
CDS_LIB"mstr_symbols"
BODY_TYPE"PLUMBING"
HDL_POWER"PVCCIO_CPU0";
"G\NAC"11;
%"P3V3_STBY"
"1","(-1125,2050)","0","mstr_symbols","I148";
;
VOLTAGE"+3.3V"
CDS_LIB"mstr_symbols"
SIZE"1B"
BODY_TYPE"PLUMBING"
HDL_POWER"P3V3_STBY";
"G\NAC"12;
%"P3V3_STBY"
"1","(-1350,800)","0","mstr_symbols","I149";
;
VOLTAGE"+3.3V"
SIZE"1B"
CDS_LIB"mstr_symbols"
BODY_TYPE"PLUMBING"
HDL_POWER"P3V3_STBY";
"G\NAC"13;
%"GND"
"1","(2175,4450)","0","mstr_symbols","I39";
;
VOLTAGE"0.0V"
BOM_COST"DEBUG"
CDS_LIB"mstr_symbols"
SIZE"1B"
ROOM"CPU_JTAG_DEBUG"
BODY_TYPE"PLUMBING"
HDL_POWER"GND";
"A\NAC"14;
%"NC7SB3157"
"1","(2600,4675)","2","mstr_analog","I40";
;
CDS_LOCATION"U1M7"
MATERIAL"IC"
PACK_TYPE"SMLF"
PART_NUMBER"C99406-001"
LOCATION"U1M7"
ROOM"DEBUG"
$SEC"1"
CDS_SEC"1"
CDS_LIB"mstr_analog"
BOM_COST"DEBUG";
"GND"
$PN"2"14;
"A"
$PN"4"62;
"VCC"
$PN"5"10;
"B1"
$PN"1"64;
"B0"
$PN"3"63;
"S"
$PN"6"65;
%"CAP_A"
"1","(3100,4025)","2","dev_discrete","I42";
;
CDS_LOCATION"C1M36"
LOCATION"C1M36"
PART_NUMBER"A36096-045"
VALUE"0.01UF"
TOLERANCE"10%"
PACK_TYPE"0402V"
VOLTAGE"25V"
MATERIAL"X7R"
BOM_COST"DEBUG"
CDS_LIB"dev_discrete"
CDS_SEC"1"
SEC_TYPE"0402V"
SEC"1"
ROOM"DEBUG";
"B"
$PN"2"15;
"A"
$PN"1"10;
%"CAP_A"
"1","(2700,4025)","2","dev_discrete","I47";
;
CDS_LOCATION"C1M37"
PART_NUMBER"D97712-004"
VALUE"1.0UF"
PACK_TYPE"0402V"
MATERIAL"X6S"
TOLERANCE"10%"
VOLTAGE"6.3V"
LOCATION"C1M37"
BOM_COST"DEBUG"
CDS_LIB"dev_discrete"
CDS_SEC"1"
$SEC"1"
ROOM"DEBUG";
"B"
$PN"2"15;
"A"
$PN"1"10;
%"GND"
"1","(2700,3675)","0","mstr_symbols","I48";
;
VOLTAGE"0.0V"
BOM_COST"DEBUG"
CDS_LIB"mstr_symbols"
SIZE"1B"
ROOM"CPU_JTAG_DEBUG"
BODY_TYPE"PLUMBING"
HDL_POWER"GND";
"A\NAC"15;
%"RES"
"2","(2675,2400)","0","mstr_discrete","I49";
;
CDS_SEC"1"
LOCATION"R6P46"
VALUE"100.0"
TOLERANCE"1%"
PACK_TYPE"0402"
MATERIAL"CHIP"
WATTAGE"1/16W"
PART_NUMBER"G21796-017"
CDS_LIB"mstr_discrete"
SEC_TYPE"0402"
SEC"1"
CDS_LOCATION"R6P46"
ROOM"DEBUG";
"A"
$PN"1"11;
"B"
$PN"2"57;
%"RES"
"2","(2325,2400)","0","mstr_discrete","I50";
;
CDS_SEC"1"
LOCATION"R7P30"
PART_NUMBER"G21796-017"
VALUE"100.0"
PACK_TYPE"0402"
WATTAGE"1/16W"
TOLERANCE"1%"
MATERIAL"CHIP"
CDS_LIB"mstr_discrete"
SEC_TYPE"0402"
SEC"1"
CDS_LOCATION"R7P30"
ROOM"DEBUG";
"A"
$PN"1"11;
"B"
$PN"2"56;
%"RES"
"2","(1950,2400)","0","mstr_discrete","I51";
;
CDS_SEC"1"
LOCATION"R1M3"
PART_NUMBER"G21796-017"
VALUE"100.0"
TOLERANCE"1%"
PACK_TYPE"0402"
MATERIAL"CHIP"
WATTAGE"1/16W"
CDS_LIB"mstr_discrete"
SEC_TYPE"0402"
SEC"1"
CDS_LOCATION"R1M3"
ROOM"DEBUG";
"A"
$PN"1"2;
"B"
$PN"2"47;
%"PVCCIO_CPU0"
"1","(1175,4150)","0","mstr_symbols","I52";
;
VOLTAGE"1.1V"
CDS_LIB"mstr_symbols"
BODY_TYPE"PLUMBING"
HDL_POWER"PVCCIO_CPU0";
"G\NAC"16;
%"RES"
"2","(1175,3800)","0","mstr_discrete","I53";
;
CDS_SEC"1"
LOCATION"R4P15"
PART_NUMBER"G21796-017"
VALUE"100.0"
TOLERANCE"1%"
PACK_TYPE"0402"
MATERIAL"CHIP"
WATTAGE"1/16W"
CDS_LIB"mstr_discrete"
SEC_TYPE"0402"
SEC"1"
CDS_LOCATION"R4P15"
ROOM"DEBUG";
"A"
$PN"1"16;
"B"
$PN"2"55;
%"RES"
"2","(1600,2400)","0","mstr_discrete","I54";
;
CDS_SEC"1"
LOCATION"R1M4"
PART_NUMBER"G21796-017"
VALUE"100.0"
TOLERANCE"1%"
PACK_TYPE"0402"
MATERIAL"CHIP"
WATTAGE"1/16W"
CDS_LIB"mstr_discrete"
SEC_TYPE"0402"
SEC"1"
CDS_LOCATION"R1M4"
ROOM"DEBUG";
"A"
$PN"1"2;
"B"
$PN"2"48;
%"RES"
"2","(1225,2400)","0","mstr_discrete","I55";
;
CDS_SEC"1"
LOCATION"R6T7"
PART_NUMBER"G21796-009"
VALUE"150.0"
TOLERANCE"1%"
PACK_TYPE"0402"
MATERIAL"CHIP"
WATTAGE"1/16W"
SEC_TYPE"0402"
CDS_LIB"mstr_discrete"
SEC"1"
CDS_LOCATION"R6T7"
ROOM"DEBUG";
"A"
$PN"1"6;
"B"
$PN"2"54;
%"RES"
"2","(875,2400)","0","mstr_discrete","I56";
;
CDS_SEC"1"
LOCATION"R6T6"
PART_NUMBER"G21796-009"
VALUE"150.0"
TOLERANCE"1%"
PACK_TYPE"0402"
MATERIAL"CHIP"
WATTAGE"1/16W"
SEC_TYPE"0402"
CDS_LIB"mstr_discrete"
SEC"1"
CDS_LOCATION"R6T6"
ROOM"DEBUG";
"A"
$PN"1"6;
"B"
$PN"2"50;
%"RES"
"2","(875,3825)","0","mstr_discrete","I57";
;
CDS_SEC"1"
LOCATION"R4P12"
PART_NUMBER"G21796-017"
VALUE"100.0"
TOLERANCE"1%"
PACK_TYPE"0402"
MATERIAL"CHIP"
WATTAGE"1/16W"
CDS_LIB"mstr_discrete"
SEC_TYPE"0402"
SEC"1"
CDS_LOCATION"R4P12"
ROOM"DEBUG";
"A"
$PN"1"16;
"B"
$PN"2"53;
%"RES"
"2","(575,3800)","0","mstr_discrete","I58";
;
CDS_SEC"1"
LOCATION"R4P23"
PART_NUMBER"G21796-009"
VALUE"150.0"
TOLERANCE"1%"
PACK_TYPE"0402"
MATERIAL"CHIP"
WATTAGE"1/16W"
SEC_TYPE"0402"
CDS_LIB"mstr_discrete"
SEC"1"
CDS_LOCATION"R4P23"
ROOM"DEBUG";
"A"
$PN"1"16;
"B"
$PN"2"52;
%"RES"
"2","(275,3800)","0","mstr_discrete","I59";
;
CDS_SEC"1"
LOCATION"R4P24"
PART_NUMBER"G21796-009"
VALUE"150.0"
TOLERANCE"1%"
PACK_TYPE"0402"
MATERIAL"CHIP"
WATTAGE"1/16W"
CDS_LIB"mstr_discrete"
SEC_TYPE"0402"
SEC"1"
CDS_LOCATION"R4P24"
ROOM"DEBUG";
"A"
$PN"1"16;
"B"
$PN"2"51;
%"RES"
"2","(500,2400)","0","mstr_discrete","I60";
;
CDS_SEC"1"
PART_NUMBER"G21796-009"
VALUE"150.0"
TOLERANCE"1%"
PACK_TYPE"0402"
MATERIAL"CHIP"
WATTAGE"1/16W"
LOCATION"R1L15"
SEC_TYPE"0402"
CDS_LIB"mstr_discrete"
SEC"1"
CDS_LOCATION"R1L15"
ROOM"DEBUG";
"A"
$PN"1"5;
"B"
$PN"2"49;
%"RES"
"2","(875,1100)","0","mstr_discrete","I61";
;
LOCATION"R7P29"
PART_NUMBER"G21796-208"
VALUE"51.1"
TOLERANCE"1.0%"
PACK_TYPE"0402"
MATERIAL"CHIP"
WATTAGE"1/16W"
CDS_LIB"mstr_discrete"
BOM_COST"DEBUG"
CDS_SEC"1"
$SEC"1"
CDS_LOCATION"R7P29"
ROOM"DEBUG";
"A"
$PN"1"46;
"B"
$PN"2"17;
%"RES"
"2","(500,1100)","0","mstr_discrete","I62";
;
CDS_SEC"1"
LOCATION"R6T5"
PART_NUMBER"G21796-026"
VALUE"1.00K"
TOLERANCE"1%"
PACK_TYPE"0402"
MATERIAL"CHIP"
WATTAGE"1/16W"
BOM_COST"DEBUG"
CDS_LIB"mstr_discrete"
SEC_TYPE"0402"
SEC"1"
CDS_LOCATION"R6T5"
ROOM"DEBUG";
"A"
$PN"1"21;
"B"
$PN"2"17;
%"GND"
"1","(500,725)","0","mstr_symbols","I74";
;
VOLTAGE"0.0V"
SIZE"1B"
CDS_LIB"mstr_symbols"
BODY_TYPE"PLUMBING"
HDL_POWER"GND";
"A\NAC"17;
%"RES"
"2","(-1200,4425)","0","mstr_discrete","I76";
;
CDS_SEC"1"
LOCATION"R1L39"
PART_NUMBER"G21796-017"
VALUE"100.0"
PACK_TYPE"0402"
WATTAGE"1/16W"
MATERIAL"CHIP"
TOLERANCE"1%"
CDS_LIB"mstr_discrete"
SEC_TYPE"0402"
SEC"1"
CDS_LOCATION"R1L39"
ROOM"DEBUG";
"A"
$PN"1"3;
"B"
$PN"2"41;
%"RES"
"2","(-1575,4425)","0","mstr_discrete","I77";
;
CDS_SEC"1"
LOCATION"R1L41"
PART_NUMBER"G21796-017"
VALUE"100.0"
TOLERANCE"1%"
PACK_TYPE"0402"
MATERIAL"CHIP"
WATTAGE"1/16W"
SEC_TYPE"0402"
CDS_LIB"mstr_discrete"
SEC"1"
CDS_LOCATION"R1L41"
ROOM"DEBUG";
"A"
$PN"1"3;
"B"
$PN"2"42;
%"RES"
"2","(-1950,4425)","0","mstr_discrete","I78";
;
CDS_SEC"1"
LOCATION"R9A11"
PART_NUMBER"G21796-009"
VALUE"150.0"
TOLERANCE"1%"
MATERIAL"CHIP"
WATTAGE"1/16W"
PACK_TYPE"0402"
CDS_LIB"mstr_discrete"
SEC_TYPE"0402"
SEC"1"
CDS_LOCATION"R9A11"
ROOM"DEBUG";
"A"
$PN"1"3;
"B"
$PN"2"45;
%"RES"
"2","(-2325,4425)","0","mstr_discrete","I79";
;
CDS_SEC"1"
LOCATION"R8A13"
VALUE"150.0"
TOLERANCE"1%"
PACK_TYPE"0402"
MATERIAL"CHIP"
WATTAGE"1/16W"
PART_NUMBER"G21796-009"
CDS_LIB"mstr_discrete"
SEC_TYPE"0402"
SEC"1"
CDS_LOCATION"R8A13"
ROOM"DEBUG";
"A"
$PN"1"3;
"B"
$PN"2"44;
%"RES"
"2","(-2700,4425)","0","mstr_discrete","I80";
;
CDS_SEC"1"
LOCATION"R8A14"
VALUE"150.0"
TOLERANCE"1%"
PACK_TYPE"0402"
MATERIAL"CHIP"
WATTAGE"1/16W"
PART_NUMBER"G21796-009"
CDS_LIB"mstr_discrete"
SEC_TYPE"0402"
SEC"1"
CDS_LOCATION"R8A14"
ROOM"DEBUG";
"A"
$PN"1"3;
"B"
$PN"2"43;
%"RES"
"2","(-1950,3600)","0","mstr_discrete","I85";
;
CDS_SEC"1"
PART_NUMBER"G21796-026"
VALUE"1.00K"
TOLERANCE"1%"
PACK_TYPE"0402"
MATERIAL"CHIP"
WATTAGE"1/16W"
LOCATION"R3M10"
SEC_TYPE"0402"
CDS_LIB"mstr_discrete"
BOM_COST"DEBUG"
SEC"1"
CDS_LOCATION"R3M10"
ROOM"DEBUG";
"A"
$PN"1"20;
"B"
$PN"2"18;
%"RES"
"2","(-2325,3600)","0","mstr_discrete","I94";
;
CDS_SEC"1"
LOCATION"R8B2"
PART_NUMBER"G21796-026"
VALUE"1.00K"
TOLERANCE"1%"
PACK_TYPE"0402"
MATERIAL"CHIP"
WATTAGE"1/16W"
SEC_TYPE"0402"
CDS_LIB"mstr_discrete"
BOM_COST"DEBUG"
SEC"1"
CDS_LOCATION"R8B2"
ROOM"DEBUG";
"A"
$PN"1"32;
"B"
$PN"2"18;
%"RES"
"2","(-2700,3600)","0","mstr_discrete","I95";
;
PART_NUMBER"G21796-208"
VALUE"51.1"
TOLERANCE"1.0%"
PACK_TYPE"0402"
MATERIAL"CHIP"
WATTAGE"1/16W"
LOCATION"R8B1"
BOM_COST"DEBUG"
CDS_LIB"mstr_discrete"
CDS_SEC"1"
$SEC"1"
CDS_LOCATION"R8B1"
ROOM"DEBUG";
"A"
$PN"1"31;
"B"
$PN"2"18;
%"GND"
"1","(-2700,3300)","0","mstr_symbols","I96";
;
VOLTAGE"0.0V"
SIZE"1B"
CDS_LIB"mstr_symbols"
BODY_TYPE"PLUMBING"
HDL_POWER"GND";
"A\NAC"18;
END.
